# BASEBOARD_FAB2 (Tioga Pass) — schematic parts with pin connectivity, parts 2377–2377 of 4751; source: Cadence DE-HDL packaged netlist (pstxprt.dat, pstxnet.dat, pstchip.dat)

J6U1  SCONN288_H44441003  SCONN  pkg PIP  page 46
  1  \12v\(1)  = P12V_NVDIMM_ABC
  2  VSS(93)  GROUND  = GND
  3  DQ(4)  BI  = M_B_DQ<4>
  4  VSS(92)  GROUND  = GND
  5  DQ(0)  BI  = M_B_DQ<0>
  6  VSS(91)  GROUND  = GND
  7  DQS9P  BI  = M_B_DQS_DP<9>
  8  DQS9N  BI  = M_B_DQS_DN<9>
  9  VSS(90)  GROUND  = GND
  10  DQ(6)  BI  = M_B_DQ<6>
  11  VSS(89)  GROUND  = GND
  12  DQ(2)  BI  = M_B_DQ<2>
  13  VSS(88)  GROUND  = GND
  14  DQ(12)  BI  = M_B_DQ<12>
  15  VSS(87)  GROUND  = GND
  16  DQ(8)  BI  = M_B_DQ<8>
  17  VSS(86)  GROUND  = GND
  18  DQS10P  BI  = M_B_DQS_DP<10>
  19  DQS10N  BI  = M_B_DQS_DN<10>
  20  VSS(85)  GROUND  = GND
  21  DQ(14)  BI  = M_B_DQ<14>
  22  VSS(84)  GROUND  = GND
  23  DQ(10)  BI  = M_B_DQ<10>
  24  VSS(83)  GROUND  = GND
  25  DQ(20)  BI  = M_B_DQ<20>
  26  VSS(82)  GROUND  = GND
  27  DQ(16)  BI  = M_B_DQ<16>
  28  VSS(81)  GROUND  = GND
  29  DQS11P  BI  = M_B_DQS_DP<11>
  30  DQS11N  BI  = M_B_DQS_DN<11>
  31  VSS(80)  GROUND  = GND
  32  DQ(22)  BI  = M_B_DQ<22>
  33  VSS(79)  GROUND  = GND
  34  DQ(18)  BI  = M_B_DQ<18>
  35  VSS(78)  GROUND  = GND
  36  DQ(28)  BI  = M_B_DQ<28>
  37  VSS(77)  GROUND  = GND
  38  DQ(24)  BI  = M_B_DQ<24>
  39  VSS(76)  GROUND  = GND
  40  DQS12P  BI  = M_B_DQS_DP<12>
  41  DQS12N  BI  = M_B_DQS_DN<12>
  42  VSS(75)  GROUND  = GND
  43  DQ(30)  BI  = M_B_DQ<30>
  44  VSS(74)  GROUND  = GND
  45  DQ(26)  BI  = M_B_DQ<26>
  46  VSS(73)  GROUND  = GND
  47  CB(4)  BI  = M_B_ECC<4>
  48  VSS(72)  GROUND  = GND
  49  CB(0)  BI  = M_B_ECC<0>
  50  VSS(71)  GROUND  = GND
  51  DQS17P  BI  = M_B_DQS_DP<17>
  52  DQS17N  BI  = M_B_DQS_DN<17>
  53  VSS(70)  GROUND  = GND
  54  CB(6)  BI  = M_B_ECC<6>
  55  VSS(69)  GROUND  = GND
  56  CB(2)  BI  = M_B_ECC<2>
  57  VSS(68)  GROUND  = GND
  58  RESET_N  BI  = M_ABC_RST_N
  59  VDD(25)  POWER  = PVDDQ_ABC
  60  CKE(0)  BI  = M_B_CKE<2>
  61  VDD(24)  POWER  = PVDDQ_ABC
  62  ACT_N  BI  = M_B_ACT_N
  63  BG(0)  BI  = M_B_BG<0>
  64  VDD(23)  POWER  = PVDDQ_ABC
  65  A12  BI  = M_B_MA<12>
  66  A9  BI  = M_B_MA<9>
  67  VDD(22)  POWER  = PVDDQ_ABC
  68  A8  BI  = M_B_MA<8>
  69  A6  BI  = M_B_MA<6>
  70  VDD(21)  POWER  = PVDDQ_ABC
  71  A3  BI  = M_B_MA<3>
  72  A1  BI  = M_B_MA<1>
  73  VDD(20)  POWER  = PVDDQ_ABC
  74  CK0P  BI  = M_B_CLK_DP<2>
  75  CK0N  BI  = M_B_CLK_DN<2>
  76  VDD(19)  POWER  = PVDDQ_ABC
  77  VTT(1)  POWER  = PVTT_ABC
  78  EVENT_N  BI  = FM_DIMM_EVENT_COD_N
  79  A0  BI  = M_B_MA<0>
  80  VDD(18)  POWER  = PVDDQ_ABC
  81  BA(0)  BI  = M_B_BA<0>
  82  A16_RAS_N  BI  = M_B_MA<16>
  83  VDD(17)  POWER  = PVDDQ_ABC
  84  S0_N  BI  = M_B_CS_N<4>
  85  VDD(16)  POWER  = PVDDQ_ABC
  86  A15_CAS_N  BI  = M_B_MA<15>
  87  ODT(0)  BI  = M_B_ODT<2>
  88  VDD(15)  POWER  = PVDDQ_ABC
  89  S1_N  BI  = M_B_CS_N<5>
  90  VDD(14)  POWER  = PVDDQ_ABC
  91  ODT(1)  BI  = M_B_ODT<3>
  92  VDD(13)  POWER  = PVDDQ_ABC
  93  S2_N_C(0)  BI  = M_B_CS_N<6>
  94  VSS(67)  GROUND  = GND
  95  DQ(36)  BI  = M_B_DQ<36>
  96  VSS(66)  GROUND  = GND
  97  DQ(32)  BI  = M_B_DQ<32>
  98  VSS(65)  GROUND  = GND
  99  DQS13P  BI  = M_B_DQS_DP<13>
  100  DQS13N  BI  = M_B_DQS_DN<13>
  101  VSS(64)  GROUND  = GND
  102  DQ(38)  BI  = M_B_DQ<38>
  103  VSS(63)  GROUND  = GND
  104  DQ(34)  BI  = M_B_DQ<34>
  105  VSS(62)  GROUND  = GND
  106  DQ(44)  BI  = M_B_DQ<44>
  107  VSS(61)  GROUND  = GND
  108  DQ(40)  BI  = M_B_DQ<40>
  109  VSS(60)  GROUND  = GND
  110  DQS14P  BI  = M_B_DQS_DP<14>
  111  DQS14N  BI  = M_B_DQS_DN<14>
  112  VSS(59)  GROUND  = GND
  113  DQ(46)  BI  = M_B_DQ<46>
  114  VSS(58)  GROUND  = GND
  115  DQ(42)  BI  = M_B_DQ<42>
  116  VSS(57)  GROUND  = GND
  117  DQ(52)  BI  = M_B_DQ<52>
  118  VSS(56)  GROUND  = GND
  119  DQ(48)  BI  = M_B_DQ<48>
  120  VSS(55)  GROUND  = GND
  121  DQS15P  BI  = M_B_DQS_DP<15>
  122  DQS15N  BI  = M_B_DQS_DN<15>
  123  VSS(54)  GROUND  = GND
  124  DQ(54)  BI  = M_B_DQ<54>
  125  VSS(53)  GROUND  = GND
  126  DQ(50)  BI  = M_B_DQ<50>
  127  VSS(52)  GROUND  = GND
  128  DQ(60)  BI  = M_B_DQ<60>
  129  VSS(51)  GROUND  = GND
  130  DQ(56)  BI  = M_B_DQ<56>
  131  VSS(50)  GROUND  = GND
  132  DQS16P  BI  = M_B_DQS_DP<16>
  133  DQS16N  BI  = M_B_DQS_DN<16>
  134  VSS(49)  GROUND  = GND
  135  DQ(62)  BI  = M_B_DQ<62>
  136  VSS(48)  GROUND  = GND
  137  DQ(58)  BI  = M_B_DQ<58>
  138  VSS(47)  GROUND  = GND
  139  SA(0)  BI  = PVPP_ABC
  140  SA(1)  BI  = PVPP_ABC
  141  SCL  BI  = SMB_DDR_ABC_VPP_SCL
  142  VPP(4)  POWER  = PVPP_ABC
  143  VPP(3)  POWER  = PVPP_ABC
  144  RFU(2)  BI  = TP_CH_B_DIMM_B1_RFU_2
  145  \12v\(0)  = P12V_NVDIMM_ABC
  146  VREFCA  BI  = M_B_VREF
  147  VSS(46)  GROUND  = GND
  148  DQ(5)  BI  = M_B_DQ<5>
  149  VSS(45)  GROUND  = GND
  150  DQ(1)  BI  = M_B_DQ<1>
  151  VSS(44)  GROUND  = GND
  152  DQS0N  BI  = M_B_DQS_DN<0>
  153  DQS0P  BI  = M_B_DQS_DP<0>
  154  VSS(43)  GROUND  = GND
  155  DQ(7)  BI  = M_B_DQ<7>
  156  VSS(42)  GROUND  = GND
  157  DQ(3)  BI  = M_B_DQ<3>
  158  VSS(41)  GROUND  = GND
  159  DQ(13)  BI  = M_B_DQ<13>
  160  VSS(40)  GROUND  = GND
  161  DQ(9)  BI  = M_B_DQ<9>
  162  VSS(39)  GROUND  = GND
  163  DQS1N  BI  = M_B_DQS_DN<1>
  164  DQS1P  BI  = M_B_DQS_DP<1>
  165  VSS(38)  GROUND  = GND
  166  DQ(15)  BI  = M_B_DQ<15>
  167  VSS(37)  GROUND  = GND
  168  DQ(11)  BI  = M_B_DQ<11>
  169  VSS(36)  GROUND  = GND
  170  DQ(21)  BI  = M_B_DQ<21>
  171  VSS(35)  GROUND  = GND
  172  DQ(17)  BI  = M_B_DQ<17>
  173  VSS(34)  GROUND  = GND
  174  DQS2N  BI  = M_B_DQS_DN<2>
  175  DQS2P  BI  = M_B_DQS_DP<2>
  176  VSS(33)  GROUND  = GND
  177  DQ(23)  BI  = M_B_DQ<23>
  178  VSS(32)  GROUND  = GND
  179  DQ(19)  BI  = M_B_DQ<19>
  180  VSS(31)  GROUND  = GND
  181  DQ(29)  BI  = M_B_DQ<29>
  182  VSS(30)  GROUND  = GND
  183  DQ(25)  BI  = M_B_DQ<25>
  184  VSS(29)  GROUND  = GND
  185  DQS3N  BI  = M_B_DQS_DN<3>
  186  DQS3P  BI  = M_B_DQS_DP<3>
  187  VSS(28)  GROUND  = GND
  188  DQ(31)  BI  = M_B_DQ<31>
  189  VSS(27)  GROUND  = GND
  190  DQ(27)  BI  = M_B_DQ<27>
  191  VSS(26)  GROUND  = GND
  192  CB(5)  BI  = M_B_ECC<5>
  193  VSS(25)  GROUND  = GND
  194  CB(1)  BI  = M_B_ECC<1>
  195  VSS(24)  GROUND  = GND
  196  DQS8N  BI  = M_B_DQS_DN<8>
  197  DQS8P  BI  = M_B_DQS_DP<8>
  198  VSS(23)  GROUND  = GND
  199  CB(7)  BI  = M_B_ECC<7>
  200  VSS(22)  GROUND  = GND
  201  CB(3)  BI  = M_B_ECC<3>
  202  VSS(21)  GROUND  = GND
  203  CKE(1)  BI  = M_B_CKE<3>
  204  VDD(12)  POWER  = PVDDQ_ABC
  205  RFU(0)  BI  = TP_CH_B_DIMM_B1_RFU_0
  206  VDD(11)  POWER  = PVDDQ_ABC
  207  BG(1)  BI  = M_B_BG<1>
  208  ALERT_N  BI  = M_B_ALERT_N
  209  VDD(10)  POWER  = PVDDQ_ABC
  210  A11  BI  = M_B_MA<11>
  211  A7  BI  = M_B_MA<7>
  212  VDD(9)  POWER  = PVDDQ_ABC
  213  A5  BI  = M_B_MA<5>
  214  A4  BI  = M_B_MA<4>
  215  VDD(8)  POWER  = PVDDQ_ABC
  216  A2  BI  = M_B_MA<2>
  217  VDD(7)  POWER  = PVDDQ_ABC
  218  CK1P  BI  = M_B_CLK_DP<3>
  219  CK1N  BI  = M_B_CLK_DN<3>
  220  VDD(6)  POWER  = PVDDQ_ABC
  221  VTT(0)  POWER  = PVTT_ABC
  222  PAR  BI  = M_B_PAR
  223  VDD(5)  POWER  = PVDDQ_ABC
  224  BA(1)  BI  = M_B_BA<1>
  225  A10  BI  = M_B_MA<10>
  226  VDD(4)  POWER  = PVDDQ_ABC
  227  RFU(1)  BI  = TP_CH_B_DIMM_B1_RFU_1
  228  A14_WE_N  BI  = M_B_MA<14>
  229  VDD(3)  POWER  = PVDDQ_ABC
  230  SAVE_N_NC  BI  = FM_ADR_COMPLETE_ABC_N
  231  VDD(2)  POWER  = PVDDQ_ABC
  232  A13  BI  = M_B_MA<13>
  233  VDD(1)  POWER  = PVDDQ_ABC
  234  A17  BI  = M_B_MA<17>
  235  C(2)  BI  = M_B_C<2>
  236  VDD(0)  POWER  = PVDDQ_ABC
  237  S3_N_C(1)  BI  = M_B_CS_N<7>
  238  SA(2)  BI  = GND
  239  VSS(20)  GROUND  = GND
  240  DQ(37)  BI  = M_B_DQ<37>
  241  VSS(19)  GROUND  = GND
  242  DQ(33)  BI  = M_B_DQ<33>
  243  VSS(18)  GROUND  = GND
  244  DQS4N  BI  = M_B_DQS_DN<4>
  245  DQS4P  BI  = M_B_DQS_DP<4>
  246  VSS(17)  GROUND  = GND
  247  DQ(39)  BI  = M_B_DQ<39>
  248  VSS(16)  GROUND  = GND
  249  DQ(35)  BI  = M_B_DQ<35>
  250  VSS(15)  GROUND  = GND
  251  DQ(45)  BI  = M_B_DQ<45>
  252  VSS(14)  GROUND  = GND
  253  DQ(41)  BI  = M_B_DQ<41>
  254  VSS(13)  GROUND  = GND
  255  DQS5N  BI  = M_B_DQS_DN<5>
  256  DQS5P  BI  = M_B_DQS_DP<5>
  257  VSS(12)  GROUND  = GND
  258  DQ(47)  BI  = M_B_DQ<47>
  259  VSS(11)  GROUND  = GND
  260  DQ(43)  BI  = M_B_DQ<43>
  261  VSS(10)  GROUND  = GND
  262  DQ(53)  BI  = M_B_DQ<53>
  263  VSS(9)  GROUND  = GND
  264  DQ(49)  BI  = M_B_DQ<49>
  265  VSS(8)  GROUND  = GND
  266  DQS6N  BI  = M_B_DQS_DN<6>
  267  DQS6P  BI  = M_B_DQS_DP<6>
  268  VSS(7)  GROUND  = GND
  269  DQ(55)  BI  = M_B_DQ<55>
  270  VSS(6)  GROUND  = GND
  271  DQ(51)  BI  = M_B_DQ<51>
  272  VSS(5)  GROUND  = GND
  273  DQ(61)  BI  = M_B_DQ<61>
  274  VSS(4)  GROUND  = GND
  275  DQ(57)  BI  = M_B_DQ<57>
  276  VSS(3)  GROUND  = GND
  277  DQS7N  BI  = M_B_DQS_DN<7>
  278  DQS7P  BI  = M_B_DQS_DP<7>
  279  VSS(2)  GROUND  = GND
  280  DQ(63)  BI  = M_B_DQ<63>
  281  VSS(1)  GROUND  = GND
  282  DQ(59)  BI  = M_B_DQ<59>
  283  VSS(0)  GROUND  = GND
  284  VDDSPD  BI  = PVPP_ABC
  285  SDA  BI  = SMB_DDR_ABC_VPP_SDA
  286  VPP(1)  POWER  = PVPP_ABC
  287  VPP(0)  POWER  = PVPP_ABC
  288  VPP(2)  POWER  = PVPP_ABC
